# S9S_MB_2U (Grand Teton) — schematic netlist excerpt (pin names and nets, part order shuffled) for the footprints in the layout excerpt that follows; sources: Cadence DE-HDL packaged netlist, KiCad conversion of 03242023_DA0F0TMBIJ0_F0T_Motherboard_J_brd_V01_OCP.brd

PR302  Q_RES  0 5% CHIP  pkg 0402LF  page 286 : A = PVCCIN_CPU1_VOS3 ; B = PVCCIN_CPU1
PC378  Q_CAP  22UF 16V 20% X6S  pkg C0805  page 297 : A = SW_P12V_PVCCINFAON_CPU1_FLT ; B = GND

(kicad_pcb
	(version 20260206)
	(generator "pcbnew")
	(generator_version "10.0")
	(general
		(thickness 1.6)
		(legacy_teardrops no)
	)
	(paper "A4")
	(title_block
		(title "03242023_DA0F0TMBIJ0_F0T_Motherboard_J_brd_V01_OCP.brd")
		(comment 1 "Grand Teton / footprints 4774-4775 of 6105")
	)
	(layers
		(0 "F.Cu" signal "TOP")
		(4 "In1.Cu" signal "GND")
		(6 "In2.Cu" signal "IN1")
		(8 "In3.Cu" signal "GND1")
		(10 "In4.Cu" signal "IN2")
		(12 "In5.Cu" signal "GND2")
		(14 "In6.Cu" signal "IN3")
		(16 "In7.Cu" signal "GND3")
		(18 "In8.Cu" signal "VCC")
		(20 "In9.Cu" signal "VCC1")
		(22 "In10.Cu" signal "GND4")
		(24 "In11.Cu" signal "IN4")
		(26 "In12.Cu" signal "GND5")
		(28 "In13.Cu" signal "IN5")
		(30 "In14.Cu" signal "GND6")
		(32 "In15.Cu" signal "IN6")
		(34 "In16.Cu" signal "GND7")
		(2 "B.Cu" signal "BOTTOM")
		(9 "F.Adhes" user "F.Adhesive")
		(11 "B.Adhes" user "B.Adhesive")
		(13 "F.Paste" user "Package Geometry/Pastemask Top")
		(15 "B.Paste" user "Package Geometry/Pastemask Bottom")
		(5 "F.SilkS" user "Ref Des/Silkscreen Top")
		(7 "B.SilkS" user "Ref Des/Silkscreen Bottom")
		(1 "F.Mask" user "Board Geometry/Soldermask Top")
		(3 "B.Mask" user "Board Geometry/Soldermask Bottom")
		(17 "Dwgs.User" user "User.Drawings")
		(19 "Cmts.User" user "User.Comments")
		(21 "Eco1.User" user "User.Eco1")
		(23 "Eco2.User" user "User.Eco2")
		(25 "Edge.Cuts" user "Board Geometry/Outline")
		(27 "Margin" user)
		(31 "F.CrtYd" user "Package Geometry/Place Bound Top")
		(29 "B.CrtYd" user "Package Geometry/Place Bound Bottom")
		(35 "F.Fab" user "Ref Des/Assembly Top")
		(33 "B.Fab" user "Ref Des/Assembly Bottom")
	)
	(footprint ""
		(layer "B.Cu")
		(at 109.658912 -336.186018 -90)
		(property "Reference" "PR302"
			(at 0 0 90)
			(layer "B.SilkS")
			(hide yes)
			(effects
				(font
					(size 1.27 1.27)
				)
				(justify mirror)
			)
		)
		(property "Value" ""
			(at 0 0 90)
			(layer "B.Fab")
			(effects
				(font
					(size 1.27 1.27)
				)
				(justify mirror)
			)
		)
		(duplicate_pad_numbers_are_jumpers no)
		(fp_line
			(start -0.7874 0.4064)
			(end 0.7874 0.4064)
			(stroke
				(width 0.1524)
				(type default)
			)
			(layer "B.SilkS")
		)
		(fp_line
			(start 0.7874 0.4064)
			(end 0.7874 -0.4064)
			(stroke
				(width 0.1524)
				(type default)
			)
			(layer "B.SilkS")
		)
		(fp_line
			(start -0.7874 -0.4064)
			(end -0.7874 0.4064)
			(stroke
				(width 0.1524)
				(type default)
			)
			(layer "B.SilkS")
		)
		(fp_line
			(start 0.7874 -0.4064)
			(end -0.7874 -0.4064)
			(stroke
				(width 0.1524)
				(type default)
			)
			(layer "B.SilkS")
		)
		(fp_line
			(start -0.67945 0.3048)
			(end -0.120396 0.3048)
			(stroke
				(width 0.1)
				(type default)
			)
			(layer "B.Fab")
		)
		(fp_line
			(start -0.120396 0.3048)
			(end -0.120396 0.2794)
			(stroke
				(width 0.1)
				(type default)
			)
			(layer "B.Fab")
		)
		(fp_line
			(start 0.12065 0.3048)
			(end 0.67945 0.3048)
			(stroke
				(width 0.1)
				(type default)
			)
			(layer "B.Fab")
		)
		(fp_line
			(start 0.67945 0.3048)
			(end 0.67945 -0.305054)
			(stroke
				(width 0.1)
				(type default)
			)
			(layer "B.Fab")
		)
		(fp_line
			(start -0.120396 0.2794)
			(end 0.12065 0.2794)
			(stroke
				(width 0.1)
				(type default)
			)
			(layer "B.Fab")
		)
		(fp_line
			(start 0.12065 0.2794)
			(end 0.12065 0.3048)
			(stroke
				(width 0.1)
				(type default)
			)
			(layer "B.Fab")
		)
		(fp_line
			(start -0.12065 -0.2794)
			(end -0.12065 -0.3048)
			(stroke
				(width 0.1)
				(type default)
			)
			(layer "B.Fab")
		)
		(fp_line
			(start 0.12065 -0.2794)
			(end -0.12065 -0.2794)
			(stroke
				(width 0.1)
				(type default)
			)
			(layer "B.Fab")
		)
		(fp_line
			(start -0.67945 -0.3048)
			(end -0.67945 0.3048)
			(stroke
				(width 0.1)
				(type default)
			)
			(layer "B.Fab")
		)
		(fp_line
			(start -0.12065 -0.3048)
			(end -0.67945 -0.3048)
			(stroke
				(width 0.1)
				(type default)
			)
			(layer "B.Fab")
		)
		(fp_line
			(start 0.12065 -0.305054)
			(end 0.12065 -0.2794)
			(stroke
				(width 0.1)
				(type default)
			)
			(layer "B.Fab")
		)
		(fp_line
			(start 0.67945 -0.305054)
			(end 0.12065 -0.305054)
			(stroke
				(width 0.1)
				(type default)
			)
			(layer "B.Fab")
		)
		(pad "1" smd circle
			(at 0.40005 0 90)
			(size 0 0)
			(layers "B.Cu" "B.Mask" "B.Paste")
			(net "PVCCIN_CPU1_VOS3")
		)
		(pad "2" smd circle
			(at -0.40005 0 90)
			(size 0 0)
			(layers "B.Cu" "B.Mask" "B.Paste")
			(net "PVCCIN_CPU1")
		)
	)
	(footprint ""
		(layer "B.Cu")
		(at 54.880002 -168.370758 180)
		(property "Reference" "PC378"
			(at 0 0 0)
			(layer "B.SilkS")
			(hide yes)
			(effects
				(font
					(size 1.27 1.27)
				)
				(justify mirror)
			)
		)
		(property "Value" ""
			(at 0 0 0)
			(layer "B.Fab")
			(effects
				(font
					(size 1.27 1.27)
				)
				(justify mirror)
			)
		)
		(duplicate_pad_numbers_are_jumpers no)
		(fp_line
			(start 1.524 0.762)
			(end 1.524 -0.762)
			(stroke
				(width 0.1524)
				(type default)
			)
			(layer "B.SilkS")
		)
		(fp_line
			(start 1.524 -0.762)
			(end -1.524 -0.762)
			(stroke
				(width 0.1524)
				(type default)
			)
			(layer "B.SilkS")
		)
		(fp_line
			(start -1.524 0.762)
			(end 1.524 0.762)
			(stroke
				(width 0.1524)
				(type default)
			)
			(layer "B.SilkS")
		)
		(fp_line
			(start -1.524 -0.762)
			(end -1.524 0.762)
			(stroke
				(width 0.1524)
				(type default)
			)
			(layer "B.SilkS")
		)
		(fp_line
			(start 1.1049 0.724916)
			(end -1.1049 0.724916)
			(stroke
				(width 0.1)
				(type default)
			)
			(layer "B.Fab")
		)
		(fp_line
			(start 1.1049 -0.724916)
			(end 1.1049 0.724916)
			(stroke
				(width 0.1)
				(type default)
			)
			(layer "B.Fab")
		)
		(fp_line
			(start -1.1049 0.724916)
			(end -1.1049 -0.724916)
			(stroke
				(width 0.1)
				(type default)
			)
			(layer "B.Fab")
		)
		(fp_line
			(start -1.1049 -0.724916)
			(end 1.1049 -0.724916)
			(stroke
				(width 0.1)
				(type default)
			)
			(layer "B.Fab")
		)
		(pad "1" smd rect
			(at 0.889 0 180)
			(size 1.016 1.27)
			(layers "B.Cu" "B.Mask" "B.Paste")
			(net "SW_P12V_PVCCINFAON_CPU1_FLT")
		)
		(pad "2" smd rect
			(at -0.889 0 180)
			(size 1.016 1.27)
			(layers "B.Cu" "B.Mask" "B.Paste")
			(net "GND")
		)
	)
)
